# T6G (Grand Teton) — schematic netlist excerpt (pin names and nets, part order shuffled) for the footprints in the layout excerpt that follows; sources: Cadence DE-HDL packaged netlist, KiCad conversion of 04192023_DAF0TMB3IC0_F0TG_MB_C_brd_V02_OCP.brd

R74  Q_RES  0 5% CHIP  pkg 0402LF  page 132 : A = NCSI_BMC_TX_EN_R ; B = RMII_BMC_OCP_TX_EN
R1319  Q_RES  2K 1% EMPTY  pkg 0402LF  page 151 : A = SMB_CPU0_CPU1_APML_SCL ; B = P3V3_AUX

(kicad_pcb
	(version 20260206)
	(generator "pcbnew")
	(generator_version "10.0")
	(general
		(thickness 1.6)
		(legacy_teardrops no)
	)
	(paper "A4")
	(title_block
		(title "04192023_DAF0TMB3IC0_F0TG_MB_C_brd_V02_OCP.brd")
		(comment 1 "Grand Teton / footprints 6959-6960 of 8354")
	)
	(layers
		(0 "F.Cu" signal "TOP")
		(4 "In1.Cu" signal "GND")
		(6 "In2.Cu" signal "IN1")
		(8 "In3.Cu" signal "GND1")
		(10 "In4.Cu" signal "IN2")
		(12 "In5.Cu" signal "GND2")
		(14 "In6.Cu" signal "IN3")
		(16 "In7.Cu" signal "GND3")
		(18 "In8.Cu" signal "VCC")
		(20 "In9.Cu" signal "VCC1")
		(22 "In10.Cu" signal "GND4")
		(24 "In11.Cu" signal "IN4")
		(26 "In12.Cu" signal "GND5")
		(28 "In13.Cu" signal "IN5")
		(30 "In14.Cu" signal "GND6")
		(32 "In15.Cu" signal "IN6")
		(34 "In16.Cu" signal "GND7")
		(2 "B.Cu" signal "BOTTOM")
		(9 "F.Adhes" user "F.Adhesive")
		(11 "B.Adhes" user "B.Adhesive")
		(13 "F.Paste" user "Package Geometry/Pastemask Top")
		(15 "B.Paste" user "Package Geometry/Pastemask Bottom")
		(5 "F.SilkS" user "Ref Des/Silkscreen Top")
		(7 "B.SilkS" user "Ref Des/Silkscreen Bottom")
		(1 "F.Mask" user "Board Geometry/Soldermask Top")
		(3 "B.Mask" user "Board Geometry/Soldermask Bottom")
		(17 "Dwgs.User" user "User.Drawings")
		(19 "Cmts.User" user "User.Comments")
		(21 "Eco1.User" user "User.Eco1")
		(23 "Eco2.User" user "User.Eco2")
		(25 "Edge.Cuts" user "Board Geometry/Outline")
		(27 "Margin" user)
		(31 "F.CrtYd" user "Package Geometry/Place Bound Top")
		(29 "B.CrtYd" user "Package Geometry/Place Bound Bottom")
		(35 "F.Fab" user "Ref Des/Assembly Top")
		(33 "B.Fab" user "Ref Des/Assembly Bottom")
	)
	(footprint ""
		(layer "B.Cu")
		(at 181.525164 -23.655782 -90)
		(property "Reference" "R1319"
			(at 0 0 90)
			(layer "B.SilkS")
			(hide yes)
			(effects
				(font
					(size 1.27 1.27)
				)
				(justify mirror)
			)
		)
		(property "Value" ""
			(at 0 0 90)
			(layer "B.Fab")
			(effects
				(font
					(size 1.27 1.27)
				)
				(justify mirror)
			)
		)
		(duplicate_pad_numbers_are_jumpers no)
		(fp_line
			(start -0.7874 0.4064)
			(end 0.7874 0.4064)
			(stroke
				(width 0.1524)
				(type default)
			)
			(layer "B.SilkS")
		)
		(fp_line
			(start 0.7874 0.4064)
			(end 0.7874 -0.4064)
			(stroke
				(width 0.1524)
				(type default)
			)
			(layer "B.SilkS")
		)
		(fp_line
			(start -0.7874 -0.4064)
			(end -0.7874 0.4064)
			(stroke
				(width 0.1524)
				(type default)
			)
			(layer "B.SilkS")
		)
		(fp_line
			(start 0.7874 -0.4064)
			(end -0.7874 -0.4064)
			(stroke
				(width 0.1524)
				(type default)
			)
			(layer "B.SilkS")
		)
		(fp_line
			(start -0.67945 0.3048)
			(end -0.120396 0.3048)
			(stroke
				(width 0.1)
				(type default)
			)
			(layer "B.Fab")
		)
		(fp_line
			(start -0.120396 0.3048)
			(end -0.120396 0.2794)
			(stroke
				(width 0.1)
				(type default)
			)
			(layer "B.Fab")
		)
		(fp_line
			(start 0.12065 0.3048)
			(end 0.67945 0.3048)
			(stroke
				(width 0.1)
				(type default)
			)
			(layer "B.Fab")
		)
		(fp_line
			(start 0.67945 0.3048)
			(end 0.67945 -0.305054)
			(stroke
				(width 0.1)
				(type default)
			)
			(layer "B.Fab")
		)
		(fp_line
			(start -0.120396 0.2794)
			(end 0.12065 0.2794)
			(stroke
				(width 0.1)
				(type default)
			)
			(layer "B.Fab")
		)
		(fp_line
			(start 0.12065 0.2794)
			(end 0.12065 0.3048)
			(stroke
				(width 0.1)
				(type default)
			)
			(layer "B.Fab")
		)
		(fp_line
			(start -0.12065 -0.2794)
			(end -0.12065 -0.3048)
			(stroke
				(width 0.1)
				(type default)
			)
			(layer "B.Fab")
		)
		(fp_line
			(start 0.12065 -0.2794)
			(end -0.12065 -0.2794)
			(stroke
				(width 0.1)
				(type default)
			)
			(layer "B.Fab")
		)
		(fp_line
			(start -0.67945 -0.3048)
			(end -0.67945 0.3048)
			(stroke
				(width 0.1)
				(type default)
			)
			(layer "B.Fab")
		)
		(fp_line
			(start -0.12065 -0.3048)
			(end -0.67945 -0.3048)
			(stroke
				(width 0.1)
				(type default)
			)
			(layer "B.Fab")
		)
		(fp_line
			(start 0.12065 -0.305054)
			(end 0.12065 -0.2794)
			(stroke
				(width 0.1)
				(type default)
			)
			(layer "B.Fab")
		)
		(fp_line
			(start 0.67945 -0.305054)
			(end 0.12065 -0.305054)
			(stroke
				(width 0.1)
				(type default)
			)
			(layer "B.Fab")
		)
		(pad "1" smd circle
			(at 0.40005 0 90)
			(size 0 0)
			(layers "B.Cu" "B.Mask" "B.Paste")
			(net "SMB_CPU0_CPU1_APML_SCL")
		)
		(pad "2" smd circle
			(at -0.40005 0 90)
			(size 0 0)
			(layers "B.Cu" "B.Mask" "B.Paste")
			(net "P3V3_AUX")
		)
	)
	(footprint ""
		(layer "B.Cu")
		(at 204.438758 -68.229734)
		(property "Reference" "R74"
			(at 0 0 0)
			(layer "B.SilkS")
			(hide yes)
			(effects
				(font
					(size 1.27 1.27)
				)
				(justify mirror)
			)
		)
		(property "Value" ""
			(at 0 0 0)
			(layer "B.Fab")
			(effects
				(font
					(size 1.27 1.27)
				)
				(justify mirror)
			)
		)
		(duplicate_pad_numbers_are_jumpers no)
		(fp_line
			(start -0.7874 -0.4064)
			(end -0.7874 0.4064)
			(stroke
				(width 0.1524)
				(type default)
			)
			(layer "B.SilkS")
		)
		(fp_line
			(start -0.7874 0.4064)
			(end 0.7874 0.4064)
			(stroke
				(width 0.1524)
				(type default)
			)
			(layer "B.SilkS")
		)
		(fp_line
			(start 0.7874 -0.4064)
			(end -0.7874 -0.4064)
			(stroke
				(width 0.1524)
				(type default)
			)
			(layer "B.SilkS")
		)
		(fp_line
			(start 0.7874 0.4064)
			(end 0.7874 -0.4064)
			(stroke
				(width 0.1524)
				(type default)
			)
			(layer "B.SilkS")
		)
		(fp_line
			(start -0.67945 -0.3048)
			(end -0.67945 0.3048)
			(stroke
				(width 0.1)
				(type default)
			)
			(layer "B.Fab")
		)
		(fp_line
			(start -0.67945 0.3048)
			(end -0.120396 0.3048)
			(stroke
				(width 0.1)
				(type default)
			)
			(layer "B.Fab")
		)
		(fp_line
			(start -0.12065 -0.3048)
			(end -0.67945 -0.3048)
			(stroke
				(width 0.1)
				(type default)
			)
			(layer "B.Fab")
		)
		(fp_line
			(start -0.12065 -0.2794)
			(end -0.12065 -0.3048)
			(stroke
				(width 0.1)
				(type default)
			)
			(layer "B.Fab")
		)
		(fp_line
			(start -0.120396 0.2794)
			(end 0.12065 0.2794)
			(stroke
				(width 0.1)
				(type default)
			)
			(layer "B.Fab")
		)
		(fp_line
			(start -0.120396 0.3048)
			(end -0.120396 0.2794)
			(stroke
				(width 0.1)
				(type default)
			)
			(layer "B.Fab")
		)
		(fp_line
			(start 0.12065 -0.305054)
			(end 0.12065 -0.2794)
			(stroke
				(width 0.1)
				(type default)
			)
			(layer "B.Fab")
		)
		(fp_line
			(start 0.12065 -0.2794)
			(end -0.12065 -0.2794)
			(stroke
				(width 0.1)
				(type default)
			)
			(layer "B.Fab")
		)
		(fp_line
			(start 0.12065 0.2794)
			(end 0.12065 0.3048)
			(stroke
				(width 0.1)
				(type default)
			)
			(layer "B.Fab")
		)
		(fp_line
			(start 0.12065 0.3048)
			(end 0.67945 0.3048)
			(stroke
				(width 0.1)
				(type default)
			)
			(layer "B.Fab")
		)
		(fp_line
			(start 0.67945 -0.305054)
			(end 0.12065 -0.305054)
			(stroke
				(width 0.1)
				(type default)
			)
			(layer "B.Fab")
		)
		(fp_line
			(start 0.67945 0.3048)
			(end 0.67945 -0.305054)
			(stroke
				(width 0.1)
				(type default)
			)
			(layer "B.Fab")
		)
		(pad "1" smd circle
			(at 0.40005 0 180)
			(size 0 0)
			(layers "B.Cu" "B.Mask" "B.Paste")
			(net "NCSI_BMC_TX_EN_R")
		)
		(pad "2" smd circle
			(at -0.40005 0 180)
			(size 0 0)
			(layers "B.Cu" "B.Mask" "B.Paste")
			(net "RMII_BMC_OCP_TX_EN")
		)
	)
)
